FILE_TYPE = CONNECTIVITY;
{Allegro Design Entry HDL 16.6-p007 (v16-6-112F) 10/10/2012}
"PAGE_NUMBER" = 109;
0"NC";
1"P3E_CPU0_PE1_SS_R_RXP<7:0>";
2"P3E_CPU0_PE1_PCH_CON_RXP<15:8>";
3"P3E_CPU0_PE1_SS_R_RXN<7:0>";
4"P3E_CPU0_PE1_SS_C_TXN<7:0>";
5"P3E_CPU0_PE2_SS_RXN<7:0>";
6"P3E_CPU0_PE2_SS_RXP<7:0>";
7"P3E_CPU0_PE1_SS_C_TXP<7:0>";
8"P3E_CPU0_PE2_SS_C_TXP<7:0>";
9"P3E_CPU0_PE2_SS_C_TXN<7:0>";
10"GND\g";
11"GND\g";
12"P3E_CPU0_PE1_SS_C_TXP<1>";
13"P3E_CPU0_PE1_SS_C_TXP<6>";
14"P3E_CPU0_PE1_SS_C_TXN<0>";
15"P3E_CPU0_PE2_SS_RXN<7>";
16"P3E_CPU0_PE1_SS_C_TXP<0>";
17"P3E_CPU0_PE1_SS_C_TXP<7>";
18"P3E_CPU0_PE2_SS_C_TXP<2>";
19"FM_PRSNT_2_6_N";
20"P3E_CPU0_PE1_SS_R_RXP<2>";
21"P3E_CPU0_PE2_SS_C_TXN<7>";
22"P3E_CPU0_PE2_SS_C_TXN<6>";
23"P3E_CPU0_PE2_SS_C_TXN<5>";
24"P3E_CPU0_PE2_SS_C_TXP<7>";
25"P3E_CPU0_PE2_SS_C_TXP<6>";
26"P3E_CPU0_PE2_SS_C_TXN<4>";
27"P3E_CPU0_PE2_SS_C_TXP<5>";
28"P3E_CPU0_PE2_SS_C_TXP<4>";
29"P3E_CPU0_PE2_SS_C_TXN<3>";
30"P3E_CPU0_PE2_SS_C_TXN<1>";
31"P3E_CPU0_PE2_SS_C_TXN<2>";
32"P3E_CPU0_PE2_SS_C_TXP<3>";
33"P3E_CPU0_PE2_SS_C_TXP<1>";
34"P3E_CPU0_PE2_SS_C_TXN<0>";
35"P3E_CPU0_PE1_SS_C_TXP<2>";
36"P3E_CPU0_PE2_SS_C_TXP<0>";
37"P3E_CPU0_PE1_SS_C_TXN<1>";
38"P3E_CPU0_PE1_SS_C_TXP<4>";
39"P3E_CPU0_PE1_SS_C_TXP<5>";
40"P3E_CPU0_PE1_SS_C_TXP<3>";
41"P3E_CPU0_PE1_SS_C_TXN<2>";
42"P3E_CPU0_PE1_SS_C_TXN<3>";
43"P3E_CPU0_PE1_SS_C_TXN<5>";
44"P3E_CPU0_PE1_SS_C_TXN<4>";
45"P3E_CPU0_PE2_SS_RXP<7>";
46"P3E_CPU0_PE2_SS_RXN<6>";
47"P3E_CPU0_PE2_SS_RXN<4>";
48"P3E_CPU0_PE2_SS_RXN<5>";
49"P3E_CPU0_PE2_SS_RXP<6>";
50"P3E_CPU0_PE2_SS_RXP<5>";
51"P3E_CPU0_PE2_SS_RXP<4>";
52"P3E_CPU0_PE2_SS_RXN<3>";
53"P3E_CPU0_PE2_SS_RXN<2>";
54"P3E_CPU0_PE2_SS_RXN<1>";
55"P3E_CPU0_PE2_SS_RXP<3>";
56"P3E_CPU0_PE2_SS_RXP<2>";
57"P3E_CPU0_PE2_SS_RXP<1>";
58"P3E_CPU0_PE2_SS_RXP<0>";
59"P3E_CPU0_PE1_SS_R_RXN<0>";
60"P3E_CPU0_PE2_SS_RXN<0>";
61"P3E_CPU0_PE1_SS_R_RXN<1>";
62"P3E_CPU0_PE1_SS_R_RXN<2>";
63"P3E_CPU0_PE1_SS_R_RXP<0>";
64"P3E_CPU0_PE1_SS_R_RXP<1>";
65"P3E_CPU0_PE1_SS_R_RXN<3>";
66"P3E_CPU0_PE1_SS_R_RXN<5>";
67"P3E_CPU0_PE1_SS_R_RXN<4>";
68"P3E_CPU0_PE1_SS_R_RXP<3>";
69"P3E_CPU0_PE1_SS_R_RXP<4>";
70"P3E_CPU0_PE1_SS_R_RXP<5>";
71"P3E_CPU0_PE1_SS_C_TXN<7>";
72"P3E_CPU0_PE1_SS_C_TXN<6>";
73"P3E_CPU0_PE1_SS_R_RXN<7>";
74"P3E_CPU0_PE1_SS_R_RXN<6>";
75"P3E_CPU0_PE1_PCH_CON_RXP<8>";
76"P3E_CPU0_PE1_SS_R_RXP<6>";
77"P3E_CPU0_PE1_SS_R_RXP<7>";
%"TAP"
"1","(-2050,2350)","2","mstr_standard","I10";
;
CDS_LIB"mstr_standard"
BODY_TYPE"PLUMBING"
HDL_TAP"TRUE";
"B \NAC \NWC"8;
"S \NAC"
BN"5"27;
%"TAP"
"1","(-2300,2400)","2","mstr_standard","I11";
;
CDS_LIB"mstr_standard"
BODY_TYPE"PLUMBING"
HDL_TAP"TRUE";
"B \NAC \NWC"9;
"S \NAC"
BN"5"23;
%"TAP"
"1","(-2300,2550)","2","mstr_standard","I12";
;
CDS_LIB"mstr_standard"
BODY_TYPE"PLUMBING"
HDL_TAP"TRUE";
"B \NAC \NWC"9;
"S \NAC"
BN"4"26;
%"TAP"
"1","(-2300,2700)","2","mstr_standard","I13";
;
CDS_LIB"mstr_standard"
BODY_TYPE"PLUMBING"
HDL_TAP"TRUE";
"B \NAC \NWC"9;
"S \NAC"
BN"3"29;
%"TAP"
"1","(-2300,2850)","2","mstr_standard","I14";
;
CDS_LIB"mstr_standard"
BODY_TYPE"PLUMBING"
HDL_TAP"TRUE";
"B \NAC \NWC"9;
"S \NAC"
BN"2"31;
%"TAP"
"1","(-2300,2950)","2","mstr_standard","I15";
;
CDS_LIB"mstr_standard"
BODY_TYPE"PLUMBING"
HDL_TAP"TRUE";
"B \NAC \NWC"9;
"S \NAC"
BN"1"30;
%"TAP"
"1","(-2300,3150)","2","mstr_standard","I16";
;
CDS_LIB"mstr_standard"
BODY_TYPE"PLUMBING"
HDL_TAP"TRUE";
"B \NAC \NWC"9;
"S \NAC"
BN"0"34;
%"TAP"
"1","(-2300,3250)","2","mstr_standard","I17";
;
CDS_LIB"mstr_standard"
BODY_TYPE"PLUMBING"
HDL_TAP"TRUE";
"B \NAC \NWC"7;
"S \NAC"
BN"0"16;
%"TAP"
"1","(-2050,2650)","2","mstr_standard","I18";
;
CDS_LIB"mstr_standard"
BODY_TYPE"PLUMBING"
HDL_TAP"TRUE";
"B \NAC \NWC"8;
"S \NAC"
BN"3"32;
%"TAP"
"1","(-2050,2500)","2","mstr_standard","I19";
;
CDS_LIB"mstr_standard"
BODY_TYPE"PLUMBING"
HDL_TAP"TRUE";
"B \NAC \NWC"8;
"S \NAC"
BN"4"28;
%"TAP"
"1","(-2050,2800)","2","mstr_standard","I20";
;
CDS_LIB"mstr_standard"
BODY_TYPE"PLUMBING"
HDL_TAP"TRUE";
"B \NAC \NWC"8;
"S \NAC"
BN"2"18;
%"TAP"
"1","(-2050,3000)","2","mstr_standard","I21";
;
CDS_LIB"mstr_standard"
BODY_TYPE"PLUMBING"
HDL_TAP"TRUE";
"B \NAC \NWC"8;
"S \NAC"
BN"1"33;
%"TAP"
"1","(-2050,3100)","2","mstr_standard","I22";
;
CDS_LIB"mstr_standard"
BODY_TYPE"PLUMBING"
HDL_TAP"TRUE";
"B \NAC \NWC"8;
"S \NAC"
BN"0"36;
%"TAP"
"1","(-2050,3300)","2","mstr_standard","I23";
;
CDS_LIB"mstr_standard"
BODY_TYPE"PLUMBING"
HDL_TAP"TRUE";
"B \NAC \NWC"4;
"S \NAC"
BN"0"14;
%"GND"
"1","(-1525,1700)","0","mstr_symbols","I25";
;
SIZE"1B"
CDS_LIB"mstr_symbols"
VOLTAGE"0"
BODY_TYPE"PLUMBING"
HDL_POWER"GND";
"A\NAC"10;
%"GND"
"1","(-475,1700)","0","mstr_symbols","I26";
;
CDS_LIB"mstr_symbols"
SIZE"1B"
VOLTAGE"0"
BODY_TYPE"PLUMBING"
HDL_POWER"GND";
"A\NAC"11;
%"TAP"
"1","(-275,2050)","0","mstr_standard","I27";
;
CDS_LIB"mstr_standard"
BODY_TYPE"PLUMBING"
HDL_TAP"TRUE";
"B \NAC \NWC"5;
"S \NAC"
BN"7"15;
%"TAP"
"1","(-275,2350)","0","mstr_standard","I28";
;
CDS_LIB"mstr_standard"
BODY_TYPE"PLUMBING"
HDL_TAP"TRUE";
"B \NAC \NWC"5;
"S \NAC"
BN"5"48;
%"TAP"
"1","(-275,2150)","0","mstr_standard","I29";
;
CDS_LIB"mstr_standard"
BODY_TYPE"PLUMBING"
HDL_TAP"TRUE";
"B \NAC \NWC"5;
"S \NAC"
BN"6"46;
%"TAP"
"1","(-50,2000)","0","mstr_standard","I30";
;
CDS_LIB"mstr_standard"
BODY_TYPE"PLUMBING"
HDL_TAP"TRUE";
"B \NAC \NWC"6;
"S \NAC"
BN"7"45;
%"TAP"
"1","(-50,2300)","0","mstr_standard","I31";
;
CDS_LIB"mstr_standard"
BODY_TYPE"PLUMBING"
HDL_TAP"TRUE";
"B \NAC \NWC"6;
"S \NAC"
BN"5"50;
%"TAP"
"1","(-50,2200)","0","mstr_standard","I32";
;
CDS_LIB"mstr_standard"
BODY_TYPE"PLUMBING"
HDL_TAP"TRUE";
"B \NAC \NWC"6;
"S \NAC"
BN"6"49;
%"TAP"
"1","(-275,2500)","0","mstr_standard","I33";
;
CDS_LIB"mstr_standard"
BODY_TYPE"PLUMBING"
HDL_TAP"TRUE";
"B \NAC \NWC"5;
"S \NAC"
BN"4"47;
%"TAP"
"1","(-275,2650)","0","mstr_standard","I34";
;
CDS_LIB"mstr_standard"
BODY_TYPE"PLUMBING"
HDL_TAP"TRUE";
"B \NAC \NWC"5;
"S \NAC"
BN"3"52;
%"TAP"
"1","(-275,3100)","0","mstr_standard","I36";
;
CDS_LIB"mstr_standard"
BODY_TYPE"PLUMBING"
HDL_TAP"TRUE";
"B \NAC \NWC"5;
"S \NAC"
BN"0"60;
%"TAP"
"1","(-275,3250)","0","mstr_standard","I37";
;
CDS_LIB"mstr_standard"
BODY_TYPE"PLUMBING"
HDL_TAP"TRUE";
"B \NAC \NWC"3;
"S \NAC"
BN"0"59;
%"TAP"
"1","(-275,3400)","0","mstr_standard","I38";
;
CDS_LIB"mstr_standard"
BODY_TYPE"PLUMBING"
HDL_TAP"TRUE";
"B \NAC \NWC"3;
"S \NAC"
BN"1"61;
%"TAP"
"1","(-50,2450)","0","mstr_standard","I39";
;
CDS_LIB"mstr_standard"
BODY_TYPE"PLUMBING"
HDL_TAP"TRUE";
"B \NAC \NWC"6;
"S \NAC"
BN"4"51;
%"TAP"
"1","(-50,2900)","0","mstr_standard","I41";
;
CDS_LIB"mstr_standard"
BODY_TYPE"PLUMBING"
HDL_TAP"TRUE";
"B \NAC \NWC"6;
"S \NAC"
BN"1"57;
%"TAP"
"1","(-50,3050)","0","mstr_standard","I42";
;
CDS_LIB"mstr_standard"
BODY_TYPE"PLUMBING"
HDL_TAP"TRUE";
"B \NAC \NWC"6;
"S \NAC"
BN"0"58;
%"TAP"
"1","(-50,3350)","0","mstr_standard","I43";
;
CDS_LIB"mstr_standard"
BODY_TYPE"PLUMBING"
HDL_TAP"TRUE";
"B \NAC \NWC"1;
"S \NAC"
BN"1"64;
%"TAP"
"1","(-50,3200)","0","mstr_standard","I44";
;
CDS_LIB"mstr_standard"
BODY_TYPE"PLUMBING"
HDL_TAP"TRUE";
"B \NAC \NWC"1;
"S \NAC"
BN"0"63;
%"TAP"
"1","(-2300,3550)","2","mstr_standard","I48";
;
CDS_LIB"mstr_standard"
BODY_TYPE"PLUMBING"
HDL_TAP"TRUE";
"B \NAC \NWC"7;
"S \NAC"
BN"2"35;
%"TAP"
"1","(-2300,3700)","2","mstr_standard","I50";
;
CDS_LIB"mstr_standard"
BODY_TYPE"PLUMBING"
HDL_TAP"TRUE";
"B \NAC \NWC"7;
"S \NAC"
BN"3"40;
%"TAP"
"1","(-2300,4000)","2","mstr_standard","I51";
;
CDS_LIB"mstr_standard"
BODY_TYPE"PLUMBING"
HDL_TAP"TRUE";
"B \NAC \NWC"7;
"S \NAC"
BN"5"39;
%"TAP"
"1","(-2300,4150)","2","mstr_standard","I52";
;
CDS_LIB"mstr_standard"
BODY_TYPE"PLUMBING"
HDL_TAP"TRUE";
"B \NAC \NWC"7;
"S \NAC"
BN"6"13;
%"TAP"
"1","(-2050,3600)","2","mstr_standard","I54";
;
CDS_LIB"mstr_standard"
BODY_TYPE"PLUMBING"
HDL_TAP"TRUE";
"B \NAC \NWC"4;
"S \NAC"
BN"2"41;
%"TAP"
"1","(-2050,3750)","2","mstr_standard","I55";
;
CDS_LIB"mstr_standard"
BODY_TYPE"PLUMBING"
HDL_TAP"TRUE";
"B \NAC \NWC"4;
"S \NAC"
BN"3"42;
%"TAP"
"1","(-2050,4050)","2","mstr_standard","I57";
;
CDS_LIB"mstr_standard"
BODY_TYPE"PLUMBING"
HDL_TAP"TRUE";
"B \NAC \NWC"4;
"S \NAC"
BN"5"43;
%"TAP"
"1","(-2050,4200)","2","mstr_standard","I58";
;
CDS_LIB"mstr_standard"
BODY_TYPE"PLUMBING"
HDL_TAP"TRUE";
"B \NAC \NWC"4;
"S \NAC"
BN"6"72;
%"TAP"
"1","(-2300,2100)","2","mstr_standard","I6";
;
CDS_LIB"mstr_standard"
BODY_TYPE"PLUMBING"
HDL_TAP"TRUE";
"B \NAC \NWC"9;
"S \NAC"
BN"7"21;
%"TAP"
"1","(-275,3700)","0","mstr_standard","I61";
;
CDS_LIB"mstr_standard"
BODY_TYPE"PLUMBING"
HDL_TAP"TRUE";
"B \NAC \NWC"3;
"S \NAC"
BN"3"65;
%"TAP"
"1","(-275,3850)","0","mstr_standard","I62";
;
CDS_LIB"mstr_standard"
BODY_TYPE"PLUMBING"
HDL_TAP"TRUE";
"B \NAC \NWC"3;
"S \NAC"
BN"4"67;
%"TAP"
"1","(-275,4000)","0","mstr_standard","I63";
;
CDS_LIB"mstr_standard"
BODY_TYPE"PLUMBING"
HDL_TAP"TRUE";
"B \NAC \NWC"3;
"S \NAC"
BN"5"66;
%"TAP"
"1","(-275,4150)","0","mstr_standard","I64";
;
CDS_LIB"mstr_standard"
BODY_TYPE"PLUMBING"
HDL_TAP"TRUE";
"B \NAC \NWC"3;
"S \NAC"
BN"6"74;
%"TAP"
"1","(-275,4300)","0","mstr_standard","I65";
;
CDS_LIB"mstr_standard"
BODY_TYPE"PLUMBING"
HDL_TAP"TRUE";
"B \NAC \NWC"3;
"S \NAC"
BN"7"73;
%"TAP"
"1","(-275,4400)","0","mstr_standard","I66";
;
CDS_LIB"mstr_standard"
BODY_TYPE"PLUMBING"
HDL_TAP"TRUE";
"B \NAC \NWC"2;
"S \NAC"
BN"8"75;
%"TAP"
"1","(-50,3650)","0","mstr_standard","I67";
;
CDS_LIB"mstr_standard"
BODY_TYPE"PLUMBING"
HDL_TAP"TRUE";
"B \NAC \NWC"1;
"S \NAC"
BN"3"68;
%"TAP"
"1","(-50,3800)","0","mstr_standard","I69";
;
CDS_LIB"mstr_standard"
BODY_TYPE"PLUMBING"
HDL_TAP"TRUE";
"B \NAC \NWC"1;
"S \NAC"
BN"4"69;
%"TAP"
"1","(-2300,2250)","2","mstr_standard","I7";
;
CDS_LIB"mstr_standard"
BODY_TYPE"PLUMBING"
HDL_TAP"TRUE";
"B \NAC \NWC"9;
"S \NAC"
BN"6"22;
%"TAP"
"1","(-50,3950)","0","mstr_standard","I70";
;
CDS_LIB"mstr_standard"
BODY_TYPE"PLUMBING"
HDL_TAP"TRUE";
"B \NAC \NWC"1;
"S \NAC"
BN"5"70;
%"TAP"
"1","(-50,4100)","0","mstr_standard","I71";
;
CDS_LIB"mstr_standard"
BODY_TYPE"PLUMBING"
HDL_TAP"TRUE";
"B \NAC \NWC"1;
"S \NAC"
BN"6"76;
%"TAP"
"1","(-50,4250)","0","mstr_standard","I72";
;
CDS_LIB"mstr_standard"
BODY_TYPE"PLUMBING"
HDL_TAP"TRUE";
"B \NAC \NWC"1;
"S \NAC"
BN"7"77;
%"TAP"
"1","(-50,2600)","0","mstr_standard","I76";
;
CDS_LIB"mstr_standard"
BODY_TYPE"PLUMBING"
HDL_TAP"TRUE";
"B \NAC \NWC"6;
"S \NAC"
BN"3"55;
%"TAP"
"1","(-275,2950)","0","mstr_standard","I77";
;
CDS_LIB"mstr_standard"
BODY_TYPE"PLUMBING"
HDL_TAP"TRUE";
"B \NAC \NWC"5;
"S \NAC"
BN"1"54;
%"SCONN200_H68296001"
"2","(-1000,3200)","0","mstr_sconn","I78";
;
CDS_SEC"2"
CDS_LOCATION"J8G1"
PART_NUMBER"H68296-001"
MATERIAL"CONN"
LOCATION"J8G1"
PACK_TYPE"SM"
ROOM"IO_SLOT"
SEC_TYPE"SM"
CDS_LIB"mstr_sconn"
CDS_LMAN_SYM_OUTLINE"-300,1350,300,-1350"
SEC"2";
"IO102"
$PN"102"75;
"IO110"
$PN"110"11;
"IO119"
$PN"119"10;
"IO117"
$PN"117"39;
"IO115"
$PN"115"43;
"IO113"
$PN"113"10;
"IO111"
$PN"111"13;
"IO109"
$PN"109"72;
"IO103"
$PN"103"17;
"IO114"
$PN"114"76;
"IO104"
$PN"104"11;
"IO106"
$PN"106"73;
"IO108"
$PN"108"77;
"IO112"
$PN"112"74;
"IO116"
$PN"116"11;
"IO118"
$PN"118"66;
"IO120"
$PN"120"70;
"IO121"
$PN"121"44;
"IO122"
$PN"122"11;
"IO123"
$PN"123"38;
"IO124"
$PN"124"67;
"IO125"
$PN"125"10;
"IO126"
$PN"126"69;
"IO127"
$PN"127"42;
"IO128"
$PN"128"11;
"IO129"
$PN"129"40;
"IO130"
$PN"130"65;
"IO131"
$PN"131"10;
"IO132"
$PN"132"68;
"IO133"
$PN"133"41;
"IO134"
$PN"134"11;
"IO135"
$PN"135"35;
"IO136"
$PN"136"62;
"IO137"
$PN"137"10;
"IO138"
$PN"138"20;
"IO139"
$PN"139"37;
"IO140"
$PN"140"11;
"IO141"
$PN"141"12;
"IO142"
$PN"142"61;
"IO143"
$PN"143"10;
"IO144"
$PN"144"64;
"IO145"
$PN"145"14;
"IO146"
$PN"146"11;
"IO147"
$PN"147"16;
"IO148"
$PN"148"59;
"IO149"
$PN"149"10;
"IO150"
$PN"150"63;
"IO151"
$PN"151"34;
"IO152"
$PN"152"11;
"IO153"
$PN"153"36;
"IO154"
$PN"154"60;
"IO155"
$PN"155"10;
"IO156"
$PN"156"58;
"IO157"
$PN"157"33;
"IO158"
$PN"158"11;
"IO159"
$PN"159"30;
"IO160"
$PN"160"54;
"IO161"
$PN"161"10;
"IO162"
$PN"162"57;
"IO163"
$PN"163"31;
"IO164"
$PN"164"11;
"IO165"
$PN"165"18;
"IO166"
$PN"166"53;
"IO167"
$PN"167"10;
"IO168"
$PN"168"56;
"IO169"
$PN"169"29;
"IO170"
$PN"170"11;
"IO171"
$PN"171"32;
"IO172"
$PN"172"52;
"IO173"
$PN"173"10;
"IO174"
$PN"174"55;
"IO175"
$PN"175"26;
"IO176"
$PN"176"11;
"IO177"
$PN"177"28;
"IO178"
$PN"178"47;
"IO179"
$PN"179"10;
"IO180"
$PN"180"51;
"IO181"
$PN"181"23;
"IO182"
$PN"182"11;
"IO183"
$PN"183"27;
"IO184"
$PN"184"48;
"IO185"
$PN"185"10;
"IO186"
$PN"186"50;
"IO187"
$PN"187"22;
"IO188"
$PN"188"11;
"IO189"
$PN"189"25;
"IO190"
$PN"190"49;
"IO191"
$PN"191"10;
"IO192"
$PN"192"46;
"IO193"
$PN"193"21;
"IO194"
$PN"194"11;
"IO195"
$PN"195"24;
"IO196"
$PN"196"15;
"IO197"
$PN"197"10;
"IO198"
$PN"198"45;
"IO199"
$PN"199"19;
"IO200"
$PN"200"11;
"IO101"
$PN"101"10;
"IO105"
$PN"105"71;
"IO107"
$PN"107"10;
%"TAP"
"1","(-2050,2050)","2","mstr_standard","I8";
;
CDS_LIB"mstr_standard"
BODY_TYPE"PLUMBING"
HDL_TAP"TRUE";
"B \NAC \NWC"8;
"S \NAC"
BN"7"24;
%"TAP"
"1","(-275,2800)","0","mstr_standard","I80";
;
CDS_LIB"mstr_standard"
BODY_TYPE"PLUMBING"
HDL_TAP"TRUE";
"B \NAC \NWC"5;
"S \NAC"
BN"2"53;
%"TAP"
"1","(-50,2750)","0","mstr_standard","I81";
;
CDS_LIB"mstr_standard"
BODY_TYPE"PLUMBING"
HDL_TAP"TRUE";
"B \NAC \NWC"6;
"S \NAC"
BN"2"56;
%"TAP"
"1","(-2050,3450)","2","mstr_standard","I82";
;
CDS_LIB"mstr_standard"
BODY_TYPE"PLUMBING"
HDL_TAP"TRUE";
"B \NAC \NWC"4;
"S \NAC"
BN"1"37;
%"TAP"
"1","(-2300,3400)","2","mstr_standard","I83";
;
CDS_LIB"mstr_standard"
BODY_TYPE"PLUMBING"
HDL_TAP"TRUE";
"B \NAC \NWC"7;
"S \NAC"
BN"1"12;
%"TAP"
"1","(-2050,3900)","2","mstr_standard","I84";
;
CDS_LIB"mstr_standard"
BODY_TYPE"PLUMBING"
HDL_TAP"TRUE";
"B \NAC \NWC"4;
"S \NAC"
BN"4"44;
%"TAP"
"1","(-2300,3850)","2","mstr_standard","I85";
;
CDS_LIB"mstr_standard"
BODY_TYPE"PLUMBING"
HDL_TAP"TRUE";
"B \NAC \NWC"7;
"S \NAC"
BN"4"38;
%"TAP"
"1","(-275,3550)","0","mstr_standard","I86";
;
CDS_LIB"mstr_standard"
BODY_TYPE"PLUMBING"
HDL_TAP"TRUE";
"B \NAC \NWC"3;
"S \NAC"
BN"2"62;
%"TAP"
"1","(-50,3500)","0","mstr_standard","I87";
;
CDS_LIB"mstr_standard"
BODY_TYPE"PLUMBING"
HDL_TAP"TRUE";
"B \NAC \NWC"1;
"S \NAC"
BN"2"20;
%"TAP"
"1","(-2050,4300)","2","mstr_standard","I88";
;
CDS_LIB"mstr_standard"
BODY_TYPE"PLUMBING"
HDL_TAP"TRUE";
"B \NAC \NWC"4;
"S \NAC"
BN"7"71;
%"TAP"
"1","(-2300,4350)","2","mstr_standard","I89";
;
CDS_LIB"mstr_standard"
BODY_TYPE"PLUMBING"
HDL_TAP"TRUE";
"B \NAC \NWC"7;
"S \NAC"
BN"7"17;
%"TAP"
"1","(-2050,2200)","2","mstr_standard","I9";
;
CDS_LIB"mstr_standard"
BODY_TYPE"PLUMBING"
HDL_TAP"TRUE";
"B \NAC \NWC"8;
"S \NAC"
BN"6"25;
END.
